(kicad_pcb
	(version 20260206)
	(generator "pcbnew")
	(generator_version "10.0")
	(general
		(thickness 1.6)
		(legacy_teardrops no)
	)
	(paper "A4")
	(title_block
		(title "Bryce Canyon_F.DPB_16315-1-OCP.brd")
		(comment 1 "Bryce Canyon / footprints 1366-1369 of 2223")
	)
	(layers
		(0 "F.Cu" signal "TOP")
		(4 "In1.Cu" signal "L2GND")
		(6 "In2.Cu" signal "L3")
		(8 "In3.Cu" signal "L4GND")
		(10 "In4.Cu" signal "L5")
		(12 "In5.Cu" signal "L6VCC")
		(14 "In6.Cu" signal "L7VCC")
		(16 "In7.Cu" signal "L8")
		(18 "In8.Cu" signal "L9GND")
		(20 "In9.Cu" signal "L10")
		(22 "In10.Cu" signal "L11GND")
		(2 "B.Cu" signal "BOTTOM")
		(9 "F.Adhes" user "F.Adhesive")
		(11 "B.Adhes" user "B.Adhesive")
		(13 "F.Paste" user "Package Geometry/Pastemask Top")
		(15 "B.Paste" user "Package Geometry/Pastemask Bottom")
		(5 "F.SilkS" user "Ref Des/Silkscreen Top")
		(7 "B.SilkS" user "Ref Des/Silkscreen Bottom")
		(1 "F.Mask" user "Board Geometry/Soldermask Top")
		(3 "B.Mask" user "Board Geometry/Soldermask Bottom")
		(17 "Dwgs.User" user "User.Drawings")
		(19 "Cmts.User" user "User.Comments")
		(21 "Eco1.User" user "User.Eco1")
		(23 "Eco2.User" user "User.Eco2")
		(25 "Edge.Cuts" user "Board Geometry/Outline")
		(27 "Margin" user)
		(31 "F.CrtYd" user "Package Geometry/Place Bound Top")
		(29 "B.CrtYd" user "Package Geometry/Place Bound Bottom")
		(35 "F.Fab" user "Ref Des/Assembly Top")
		(33 "B.Fab" user "Ref Des/Assembly Bottom")
	)
	(footprint ""
		(layer "F.Cu")
		(at 36.178998 -295.064942 90)
		(property "Reference" "R962"
			(at 0 0 90)
			(layer "F.SilkS")
			(hide yes)
			(effects
				(font
					(size 1.27 1.27)
				)
			)
		)
		(property "Value" "220R3F-1-GP"
			(at -0.0254 -2.5146 90)
			(unlocked yes)
			(layer "F.Fab")
			(hide yes)
			(effects
				(font
					(size 1.016 1.016)
					(thickness 0.1524)
				)
			)
		)
		(property "Device Type" "R603H22"
			(at -0.0254 -4.0386 90)
			(unlocked yes)
			(layer "F.Fab")
			(hide yes)
			(effects
				(font
					(size 1.016 1.016)
					(thickness 0.1524)
				)
			)
		)
		(duplicate_pad_numbers_are_jumpers no)
		(fp_line
			(start 0.2032 0)
			(end 0.4826 0)
			(stroke
				(width 0.2032)
				(type default)
			)
			(layer "F.SilkS")
		)
		(fp_line
			(start -0.4826 0)
			(end -0.2032 0)
			(stroke
				(width 0.2032)
				(type default)
			)
			(layer "F.SilkS")
		)
		(fp_rect
			(start -0.5842 1.3335)
			(end 0.5842 -1.3335)
			(stroke
				(width 0)
				(type default)
			)
			(fill no)
			(layer "F.CrtYd")
		)
		(fp_rect
			(start -0.5842 1.3335)
			(end 0.5842 -1.3335)
			(stroke
				(width 0)
				(type default)
			)
			(fill no)
			(layer "F.Fab")
		)
		(pad "1" smd custom
			(at 0 -0.762 90)
			(size 0.2159 0.2159)
			(layers "F.Cu" "F.Mask" "F.Paste")
			(net "HDD_PRSNT_0")
			(options
				(clearance outline)
				(anchor circle)
			)
			(primitives
				(gr_poly
					(pts
						(arc
							(start -0.3302 -0.4318)
							(mid -0.402042 -0.402042)
							(end -0.4318 -0.3302)
						)
						(arc
							(start -0.4318 0.3302)
							(mid -0.402042 0.402042)
							(end -0.3302 0.4318)
						)
						(arc
							(start 0.3302 0.4318)
							(mid 0.402042 0.402042)
							(end 0.4318 0.3302)
						)
						(arc
							(start 0.4318 -0.3302)
							(mid 0.402042 -0.402042)
							(end 0.3302 -0.4318)
						)
					)
					(width 0)
					(fill yes)
				)
			)
		)
		(pad "2" smd custom
			(at 0 0.762 90)
			(size 0.2159 0.2159)
			(layers "F.Cu" "F.Mask" "F.Paste")
			(net "DRIVE_A_0_INS")
			(options
				(clearance outline)
				(anchor circle)
			)
			(primitives
				(gr_poly
					(pts
						(arc
							(start -0.3302 -0.4318)
							(mid -0.402042 -0.402042)
							(end -0.4318 -0.3302)
						)
						(arc
							(start -0.4318 0.3302)
							(mid -0.402042 0.402042)
							(end -0.3302 0.4318)
						)
						(arc
							(start 0.3302 0.4318)
							(mid 0.402042 0.402042)
							(end 0.4318 0.3302)
						)
						(arc
							(start 0.4318 -0.3302)
							(mid 0.402042 -0.402042)
							(end 0.3302 -0.4318)
						)
					)
					(width 0)
					(fill yes)
				)
			)
		)
	)
	(footprint ""
		(layer "F.Cu")
		(at 127.729996 -287.241742 90)
		(property "Reference" "R203"
			(at 0 0 90)
			(layer "F.SilkS")
			(hide yes)
			(effects
				(font
					(size 1.27 1.27)
				)
			)
		)
		(property "Value" "220R3F-1-GP"
			(at -0.0254 -2.5146 90)
			(unlocked yes)
			(layer "F.Fab")
			(hide yes)
			(effects
				(font
					(size 1.016 1.016)
					(thickness 0.1524)
				)
			)
		)
		(property "Device Type" "R603H22"
			(at -0.0254 -4.0386 90)
			(unlocked yes)
			(layer "F.Fab")
			(hide yes)
			(effects
				(font
					(size 1.016 1.016)
					(thickness 0.1524)
				)
			)
		)
		(duplicate_pad_numbers_are_jumpers no)
		(fp_line
			(start 0.2032 0)
			(end 0.4826 0)
			(stroke
				(width 0.2032)
				(type default)
			)
			(layer "F.SilkS")
		)
		(fp_line
			(start -0.4826 0)
			(end -0.2032 0)
			(stroke
				(width 0.2032)
				(type default)
			)
			(layer "F.SilkS")
		)
		(fp_rect
			(start -0.5842 1.3335)
			(end 0.5842 -1.3335)
			(stroke
				(width 0)
				(type default)
			)
			(fill no)
			(layer "F.CrtYd")
		)
		(fp_rect
			(start -0.5842 1.3335)
			(end 0.5842 -1.3335)
			(stroke
				(width 0)
				(type default)
			)
			(fill no)
			(layer "F.Fab")
		)
		(pad "1" smd custom
			(at 0 -0.762 90)
			(size 0.2159 0.2159)
			(layers "F.Cu" "F.Mask" "F.Paste")
			(net "HDD_PRSNT_3")
			(options
				(clearance outline)
				(anchor circle)
			)
			(primitives
				(gr_poly
					(pts
						(arc
							(start -0.3302 -0.4318)
							(mid -0.402042 -0.402042)
							(end -0.4318 -0.3302)
						)
						(arc
							(start -0.4318 0.3302)
							(mid -0.402042 0.402042)
							(end -0.3302 0.4318)
						)
						(arc
							(start 0.3302 0.4318)
							(mid 0.402042 0.402042)
							(end 0.4318 0.3302)
						)
						(arc
							(start 0.4318 -0.3302)
							(mid 0.402042 -0.402042)
							(end 0.3302 -0.4318)
						)
					)
					(width 0)
					(fill yes)
				)
			)
		)
		(pad "2" smd custom
			(at 0 0.762 90)
			(size 0.2159 0.2159)
			(layers "F.Cu" "F.Mask" "F.Paste")
			(net "DRIVE_A_3_INS")
			(options
				(clearance outline)
				(anchor circle)
			)
			(primitives
				(gr_poly
					(pts
						(arc
							(start -0.3302 -0.4318)
							(mid -0.402042 -0.402042)
							(end -0.4318 -0.3302)
						)
						(arc
							(start -0.4318 0.3302)
							(mid -0.402042 0.402042)
							(end -0.3302 0.4318)
						)
						(arc
							(start 0.3302 0.4318)
							(mid 0.402042 0.402042)
							(end 0.4318 0.3302)
						)
						(arc
							(start 0.4318 -0.3302)
							(mid 0.402042 -0.402042)
							(end 0.3302 -0.4318)
						)
					)
					(width 0)
					(fill yes)
				)
			)
		)
	)
	(footprint ""
		(layer "F.Cu")
		(at 172.8216 -279.2222 180)
		(property "Reference" "R261"
			(at 0 0 180)
			(layer "F.SilkS")
			(hide yes)
			(effects
				(font
					(size 1.27 1.27)
				)
			)
		)
		(property "Value" "200KR2F-L-GP"
			(at 0.064008 -3.993896 180)
			(unlocked yes)
			(layer "F.Fab")
			(hide yes)
			(effects
				(font
					(size 1.016 1.016)
					(thickness 0.1524)
				)
			)
		)
		(property "Device Type" "R402H16"
			(at 0.064008 -5.517896 180)
			(unlocked yes)
			(layer "F.Fab")
			(hide yes)
			(effects
				(font
					(size 1.016 1.016)
					(thickness 0.1524)
				)
			)
		)
		(duplicate_pad_numbers_are_jumpers no)
		(fp_line
			(start 0.508 -0.9398)
			(end -0.508 -0.9398)
			(stroke
				(width 0.1524)
				(type default)
			)
			(layer "F.SilkS")
		)
		(fp_line
			(start -0.508 -0.9398)
			(end -0.508 0.9398)
			(stroke
				(width 0.1524)
				(type default)
			)
			(layer "F.SilkS")
		)
		(fp_rect
			(start -0.508 0.9398)
			(end 0.508 -0.9398)
			(stroke
				(width 0)
				(type default)
			)
			(fill no)
			(layer "F.CrtYd")
		)
		(fp_rect
			(start -0.508 0.9398)
			(end 0.508 -0.9398)
			(stroke
				(width 0)
				(type default)
			)
			(fill no)
			(layer "F.Fab")
		)
		(pad "1" smd custom
			(at 0 -0.4445 180)
			(size 0.1397 0.1397)
			(layers "F.Cu" "F.Mask" "F.Paste")
			(net "SW_HDD_R5")
			(options
				(clearance outline)
				(anchor circle)
			)
			(primitives
				(gr_poly
					(pts
						(arc
							(start -0.1778 -0.2794)
							(mid -0.249642 -0.249642)
							(end -0.2794 -0.1778)
						)
						(arc
							(start -0.2794 0.1778)
							(mid -0.249642 0.249642)
							(end -0.1778 0.2794)
						)
						(arc
							(start 0.1778 0.2794)
							(mid 0.249642 0.249642)
							(end 0.2794 0.1778)
						)
						(arc
							(start 0.2794 -0.1778)
							(mid 0.249642 -0.249642)
							(end 0.1778 -0.2794)
						)
					)
					(width 0)
					(fill yes)
				)
			)
		)
		(pad "2" smd custom
			(at 0 0.4445 180)
			(size 0.1397 0.1397)
			(layers "F.Cu" "F.Mask" "F.Paste")
			(net "SW_HDD_N5")
			(options
				(clearance outline)
				(anchor circle)
			)
			(primitives
				(gr_poly
					(pts
						(arc
							(start -0.1778 -0.2794)
							(mid -0.249642 -0.249642)
							(end -0.2794 -0.1778)
						)
						(arc
							(start -0.2794 0.1778)
							(mid -0.249642 0.249642)
							(end -0.1778 0.2794)
						)
						(arc
							(start 0.1778 0.2794)
							(mid 0.249642 0.249642)
							(end 0.2794 0.1778)
						)
						(arc
							(start 0.2794 -0.1778)
							(mid 0.249642 -0.249642)
							(end 0.1778 -0.2794)
						)
					)
					(width 0)
					(fill yes)
				)
			)
		)
	)
	(footprint ""
		(layer "F.Cu")
		(at 469.492584 -277.472902 90)
		(property "Reference" "D11"
			(at 0 0 90)
			(layer "F.SilkS")
			(hide yes)
			(effects
				(font
					(size 1.27 1.27)
				)
			)
		)
		(property "Value" "RB551V30-GP"
			(at 0 -6.7818 90)
			(unlocked yes)
			(layer "F.Fab")
			(hide yes)
			(effects
				(font
					(size 1.016 1.016)
					(thickness 0.1524)
				)
			)
		)
		(property "Device Type" "SOD323AKH38"
			(at 0 -8.6868 90)
			(unlocked yes)
			(layer "F.Fab")
			(hide yes)
			(effects
				(font
					(size 1.016 1.016)
					(thickness 0.1524)
				)
			)
		)
		(duplicate_pad_numbers_are_jumpers no)
		(fp_line
			(start 0.889 -1.9304)
			(end 0.889 2.159)
			(stroke
				(width 0.1524)
				(type default)
			)
			(layer "F.SilkS")
		)
		(fp_line
			(start -0.889 -1.9304)
			(end 0.889 -1.9304)
			(stroke
				(width 0.1524)
				(type default)
			)
			(layer "F.SilkS")
		)
		(fp_line
			(start 0.762 2.0574)
			(end -0.762 2.0574)
			(stroke
				(width 0.508)
				(type default)
			)
			(layer "F.SilkS")
		)
		(fp_line
			(start 0.889 2.159)
			(end -0.889 2.159)
			(stroke
				(width 0.1524)
				(type default)
			)
			(layer "F.SilkS")
		)
		(fp_line
			(start -0.889 2.159)
			(end -0.889 -1.9304)
			(stroke
				(width 0.1524)
				(type default)
			)
			(layer "F.SilkS")
		)
		(fp_rect
			(start -1.016 2.3114)
			(end 1.016 -2.0066)
			(stroke
				(width 0)
				(type default)
			)
			(fill no)
			(layer "F.CrtYd")
		)
		(fp_poly
			(pts
				(xy -1.016 -2.0066) (xy 1.016 -2.0066) (xy 1.016 2.3114) (xy -1.016 2.3114)
			)
			(stroke
				(width 0)
				(type default)
			)
			(fill no)
			(layer "F.Fab")
		)
		(pad "A" smd rect
			(at 0 -1.143 90)
			(size 0.5588 1.016)
			(layers "F.Cu" "F.Mask" "F.Paste")
			(net "SW_HDD_R11")
		)
		(pad "K" smd rect
			(at 0 1.143 90)
			(size 0.5588 1.016)
			(layers "F.Cu" "F.Mask" "F.Paste")
			(net "SW_HDD_N11")
		)
	)
)
